(kicad_pcb
	(version 20260206)
	(generator "pcbnew")
	(generator_version "10.0")
	(general
		(thickness 1.6)
		(legacy_teardrops no)
	)
	(paper "A4")
	(title_block
		(title "04192023_DAF0TMB3IC0_F0TG_MB_C_brd_V02_OCP.brd")
		(comment 1 "Grand Teton / footprints 6856-6862 of 8354")
	)
	(layers
		(0 "F.Cu" signal "TOP")
		(4 "In1.Cu" signal "GND")
		(6 "In2.Cu" signal "IN1")
		(8 "In3.Cu" signal "GND1")
		(10 "In4.Cu" signal "IN2")
		(12 "In5.Cu" signal "GND2")
		(14 "In6.Cu" signal "IN3")
		(16 "In7.Cu" signal "GND3")
		(18 "In8.Cu" signal "VCC")
		(20 "In9.Cu" signal "VCC1")
		(22 "In10.Cu" signal "GND4")
		(24 "In11.Cu" signal "IN4")
		(26 "In12.Cu" signal "GND5")
		(28 "In13.Cu" signal "IN5")
		(30 "In14.Cu" signal "GND6")
		(32 "In15.Cu" signal "IN6")
		(34 "In16.Cu" signal "GND7")
		(2 "B.Cu" signal "BOTTOM")
		(9 "F.Adhes" user "F.Adhesive")
		(11 "B.Adhes" user "B.Adhesive")
		(13 "F.Paste" user "Package Geometry/Pastemask Top")
		(15 "B.Paste" user "Package Geometry/Pastemask Bottom")
		(5 "F.SilkS" user "Ref Des/Silkscreen Top")
		(7 "B.SilkS" user "Ref Des/Silkscreen Bottom")
		(1 "F.Mask" user "Board Geometry/Soldermask Top")
		(3 "B.Mask" user "Board Geometry/Soldermask Bottom")
		(17 "Dwgs.User" user "User.Drawings")
		(19 "Cmts.User" user "User.Comments")
		(21 "Eco1.User" user "User.Eco1")
		(23 "Eco2.User" user "User.Eco2")
		(25 "Edge.Cuts" user "Board Geometry/Outline")
		(27 "Margin" user)
		(31 "F.CrtYd" user "Package Geometry/Place Bound Top")
		(29 "B.CrtYd" user "Package Geometry/Place Bound Bottom")
		(35 "F.Fab" user "Ref Des/Assembly Top")
		(33 "B.Fab" user "Ref Des/Assembly Bottom")
	)
	(footprint ""
		(layer "B.Cu")
		(at 353.900232 -259.355082 180)
		(property "Reference" "C2620"
			(at 0 0 0)
			(layer "B.SilkS")
			(hide yes)
			(effects
				(font
					(size 1.27 1.27)
				)
				(justify mirror)
			)
		)
		(property "Value" ""
			(at 0 0 0)
			(layer "B.Fab")
			(effects
				(font
					(size 1.27 1.27)
				)
				(justify mirror)
			)
		)
		(duplicate_pad_numbers_are_jumpers no)
		(fp_line
			(start 0.7874 0.4064)
			(end 0.7874 -0.4064)
			(stroke
				(width 0.1524)
				(type default)
			)
			(layer "B.SilkS")
		)
		(fp_line
			(start 0.7874 -0.4064)
			(end -0.7874 -0.4064)
			(stroke
				(width 0.1524)
				(type default)
			)
			(layer "B.SilkS")
		)
		(fp_line
			(start -0.7874 0.4064)
			(end 0.7874 0.4064)
			(stroke
				(width 0.1524)
				(type default)
			)
			(layer "B.SilkS")
		)
		(fp_line
			(start -0.7874 -0.4064)
			(end -0.7874 0.4064)
			(stroke
				(width 0.1524)
				(type default)
			)
			(layer "B.SilkS")
		)
		(fp_line
			(start 0.67945 0.3048)
			(end 0.67945 -0.305054)
			(stroke
				(width 0.1)
				(type default)
			)
			(layer "B.Fab")
		)
		(fp_line
			(start 0.67945 -0.305054)
			(end 0.12065 -0.305054)
			(stroke
				(width 0.1)
				(type default)
			)
			(layer "B.Fab")
		)
		(fp_line
			(start 0.12065 0.3048)
			(end 0.67945 0.3048)
			(stroke
				(width 0.1)
				(type default)
			)
			(layer "B.Fab")
		)
		(fp_line
			(start 0.12065 0.2794)
			(end 0.12065 0.3048)
			(stroke
				(width 0.1)
				(type default)
			)
			(layer "B.Fab")
		)
		(fp_line
			(start 0.12065 -0.2794)
			(end -0.12065 -0.2794)
			(stroke
				(width 0.1)
				(type default)
			)
			(layer "B.Fab")
		)
		(fp_line
			(start 0.12065 -0.305054)
			(end 0.12065 -0.2794)
			(stroke
				(width 0.1)
				(type default)
			)
			(layer "B.Fab")
		)
		(fp_line
			(start -0.120396 0.3048)
			(end -0.120396 0.2794)
			(stroke
				(width 0.1)
				(type default)
			)
			(layer "B.Fab")
		)
		(fp_line
			(start -0.120396 0.2794)
			(end 0.12065 0.2794)
			(stroke
				(width 0.1)
				(type default)
			)
			(layer "B.Fab")
		)
		(fp_line
			(start -0.12065 -0.2794)
			(end -0.12065 -0.3048)
			(stroke
				(width 0.1)
				(type default)
			)
			(layer "B.Fab")
		)
		(fp_line
			(start -0.12065 -0.3048)
			(end -0.67945 -0.3048)
			(stroke
				(width 0.1)
				(type default)
			)
			(layer "B.Fab")
		)
		(fp_line
			(start -0.67945 0.3048)
			(end -0.120396 0.3048)
			(stroke
				(width 0.1)
				(type default)
			)
			(layer "B.Fab")
		)
		(fp_line
			(start -0.67945 -0.3048)
			(end -0.67945 0.3048)
			(stroke
				(width 0.1)
				(type default)
			)
			(layer "B.Fab")
		)
		(pad "1" smd circle
			(at 0.40005 0)
			(size 0 0)
			(layers "B.Cu" "B.Mask" "B.Paste")
			(net "PVDDIO_P0")
		)
		(pad "2" smd circle
			(at -0.40005 0)
			(size 0 0)
			(layers "B.Cu" "B.Mask" "B.Paste")
			(net "GND")
		)
	)
	(footprint ""
		(layer "B.Cu")
		(at 239.522 -217.678 90)
		(property "Reference" "R1152"
			(at 0 0 90)
			(layer "B.SilkS")
			(hide yes)
			(effects
				(font
					(size 1.27 1.27)
				)
				(justify mirror)
			)
		)
		(property "Value" ""
			(at 0 0 90)
			(layer "B.Fab")
			(effects
				(font
					(size 1.27 1.27)
				)
				(justify mirror)
			)
		)
		(duplicate_pad_numbers_are_jumpers no)
		(fp_line
			(start 0.7874 -0.4064)
			(end -0.7874 -0.4064)
			(stroke
				(width 0.1524)
				(type default)
			)
			(layer "B.SilkS")
		)
		(fp_line
			(start -0.7874 -0.4064)
			(end -0.7874 0.4064)
			(stroke
				(width 0.1524)
				(type default)
			)
			(layer "B.SilkS")
		)
		(fp_line
			(start 0.7874 0.4064)
			(end 0.7874 -0.4064)
			(stroke
				(width 0.1524)
				(type default)
			)
			(layer "B.SilkS")
		)
		(fp_line
			(start -0.7874 0.4064)
			(end 0.7874 0.4064)
			(stroke
				(width 0.1524)
				(type default)
			)
			(layer "B.SilkS")
		)
		(fp_line
			(start 0.67945 -0.305054)
			(end 0.12065 -0.305054)
			(stroke
				(width 0.1)
				(type default)
			)
			(layer "B.Fab")
		)
		(fp_line
			(start 0.12065 -0.305054)
			(end 0.12065 -0.2794)
			(stroke
				(width 0.1)
				(type default)
			)
			(layer "B.Fab")
		)
		(fp_line
			(start -0.12065 -0.3048)
			(end -0.67945 -0.3048)
			(stroke
				(width 0.1)
				(type default)
			)
			(layer "B.Fab")
		)
		(fp_line
			(start -0.67945 -0.3048)
			(end -0.67945 0.3048)
			(stroke
				(width 0.1)
				(type default)
			)
			(layer "B.Fab")
		)
		(fp_line
			(start 0.12065 -0.2794)
			(end -0.12065 -0.2794)
			(stroke
				(width 0.1)
				(type default)
			)
			(layer "B.Fab")
		)
		(fp_line
			(start -0.12065 -0.2794)
			(end -0.12065 -0.3048)
			(stroke
				(width 0.1)
				(type default)
			)
			(layer "B.Fab")
		)
		(fp_line
			(start 0.12065 0.2794)
			(end 0.12065 0.3048)
			(stroke
				(width 0.1)
				(type default)
			)
			(layer "B.Fab")
		)
		(fp_line
			(start -0.120396 0.2794)
			(end 0.12065 0.2794)
			(stroke
				(width 0.1)
				(type default)
			)
			(layer "B.Fab")
		)
		(fp_line
			(start 0.67945 0.3048)
			(end 0.67945 -0.305054)
			(stroke
				(width 0.1)
				(type default)
			)
			(layer "B.Fab")
		)
		(fp_line
			(start 0.12065 0.3048)
			(end 0.67945 0.3048)
			(stroke
				(width 0.1)
				(type default)
			)
			(layer "B.Fab")
		)
		(fp_line
			(start -0.120396 0.3048)
			(end -0.120396 0.2794)
			(stroke
				(width 0.1)
				(type default)
			)
			(layer "B.Fab")
		)
		(fp_line
			(start -0.67945 0.3048)
			(end -0.120396 0.3048)
			(stroke
				(width 0.1)
				(type default)
			)
			(layer "B.Fab")
		)
		(pad "1" smd circle
			(at 0.40005 0 270)
			(size 0 0)
			(layers "B.Cu" "B.Mask" "B.Paste")
			(net "SMB_CPU0_CPU1_APML_BUF1_SDA_R1")
		)
		(pad "2" smd circle
			(at -0.40005 0 270)
			(size 0 0)
			(layers "B.Cu" "B.Mask" "B.Paste")
			(net "SMB_CPU0_CPU1_APML_BUF1_SDA_R2")
		)
	)
	(footprint ""
		(layer "B.Cu")
		(at 438.103264 -244.08511)
		(property "Reference" "R384"
			(at 0 0 0)
			(layer "B.SilkS")
			(hide yes)
			(effects
				(font
					(size 1.27 1.27)
				)
				(justify mirror)
			)
		)
		(property "Value" ""
			(at 0 0 0)
			(layer "B.Fab")
			(effects
				(font
					(size 1.27 1.27)
				)
				(justify mirror)
			)
		)
		(duplicate_pad_numbers_are_jumpers no)
		(fp_line
			(start -0.7874 -0.4064)
			(end -0.7874 0.4064)
			(stroke
				(width 0.1524)
				(type default)
			)
			(layer "B.SilkS")
		)
		(fp_line
			(start -0.7874 0.4064)
			(end 0.7874 0.4064)
			(stroke
				(width 0.1524)
				(type default)
			)
			(layer "B.SilkS")
		)
		(fp_line
			(start 0.7874 -0.4064)
			(end -0.7874 -0.4064)
			(stroke
				(width 0.1524)
				(type default)
			)
			(layer "B.SilkS")
		)
		(fp_line
			(start 0.7874 0.4064)
			(end 0.7874 -0.4064)
			(stroke
				(width 0.1524)
				(type default)
			)
			(layer "B.SilkS")
		)
		(fp_line
			(start -0.67945 -0.3048)
			(end -0.67945 0.3048)
			(stroke
				(width 0.1)
				(type default)
			)
			(layer "B.Fab")
		)
		(fp_line
			(start -0.67945 0.3048)
			(end -0.120396 0.3048)
			(stroke
				(width 0.1)
				(type default)
			)
			(layer "B.Fab")
		)
		(fp_line
			(start -0.12065 -0.3048)
			(end -0.67945 -0.3048)
			(stroke
				(width 0.1)
				(type default)
			)
			(layer "B.Fab")
		)
		(fp_line
			(start -0.12065 -0.2794)
			(end -0.12065 -0.3048)
			(stroke
				(width 0.1)
				(type default)
			)
			(layer "B.Fab")
		)
		(fp_line
			(start -0.120396 0.2794)
			(end 0.12065 0.2794)
			(stroke
				(width 0.1)
				(type default)
			)
			(layer "B.Fab")
		)
		(fp_line
			(start -0.120396 0.3048)
			(end -0.120396 0.2794)
			(stroke
				(width 0.1)
				(type default)
			)
			(layer "B.Fab")
		)
		(fp_line
			(start 0.12065 -0.305054)
			(end 0.12065 -0.2794)
			(stroke
				(width 0.1)
				(type default)
			)
			(layer "B.Fab")
		)
		(fp_line
			(start 0.12065 -0.2794)
			(end -0.12065 -0.2794)
			(stroke
				(width 0.1)
				(type default)
			)
			(layer "B.Fab")
		)
		(fp_line
			(start 0.12065 0.2794)
			(end 0.12065 0.3048)
			(stroke
				(width 0.1)
				(type default)
			)
			(layer "B.Fab")
		)
		(fp_line
			(start 0.12065 0.3048)
			(end 0.67945 0.3048)
			(stroke
				(width 0.1)
				(type default)
			)
			(layer "B.Fab")
		)
		(fp_line
			(start 0.67945 -0.305054)
			(end 0.12065 -0.305054)
			(stroke
				(width 0.1)
				(type default)
			)
			(layer "B.Fab")
		)
		(fp_line
			(start 0.67945 0.3048)
			(end 0.67945 -0.305054)
			(stroke
				(width 0.1)
				(type default)
			)
			(layer "B.Fab")
		)
		(pad "1" smd circle
			(at 0.40005 0 180)
			(size 0 0)
			(layers "B.Cu" "B.Mask" "B.Paste")
			(net "M_J_CPU0_ALERT_N")
		)
		(pad "2" smd circle
			(at -0.40005 0 180)
			(size 0 0)
			(layers "B.Cu" "B.Mask" "B.Paste")
			(net "M_J_CPU0_ALERT_R_N")
		)
	)
	(footprint ""
		(layer "B.Cu")
		(at 115.686078 -26.025856 90)
		(property "Reference" "C6116"
			(at 0 0 90)
			(layer "B.SilkS")
			(hide yes)
			(effects
				(font
					(size 1.27 1.27)
				)
				(justify mirror)
			)
		)
		(property "Value" ""
			(at 0 0 90)
			(layer "B.Fab")
			(effects
				(font
					(size 1.27 1.27)
				)
				(justify mirror)
			)
		)
		(duplicate_pad_numbers_are_jumpers no)
		(fp_line
			(start 0.7874 -0.4064)
			(end -0.7874 -0.4064)
			(stroke
				(width 0.1524)
				(type default)
			)
			(layer "B.SilkS")
		)
		(fp_line
			(start -0.7874 -0.4064)
			(end -0.7874 0.4064)
			(stroke
				(width 0.1524)
				(type default)
			)
			(layer "B.SilkS")
		)
		(fp_line
			(start 0.7874 0.4064)
			(end 0.7874 -0.4064)
			(stroke
				(width 0.1524)
				(type default)
			)
			(layer "B.SilkS")
		)
		(fp_line
			(start -0.7874 0.4064)
			(end 0.7874 0.4064)
			(stroke
				(width 0.1524)
				(type default)
			)
			(layer "B.SilkS")
		)
		(fp_line
			(start 0.67945 -0.305054)
			(end 0.12065 -0.305054)
			(stroke
				(width 0.1)
				(type default)
			)
			(layer "B.Fab")
		)
		(fp_line
			(start 0.12065 -0.305054)
			(end 0.12065 -0.2794)
			(stroke
				(width 0.1)
				(type default)
			)
			(layer "B.Fab")
		)
		(fp_line
			(start -0.12065 -0.3048)
			(end -0.67945 -0.3048)
			(stroke
				(width 0.1)
				(type default)
			)
			(layer "B.Fab")
		)
		(fp_line
			(start -0.67945 -0.3048)
			(end -0.67945 0.3048)
			(stroke
				(width 0.1)
				(type default)
			)
			(layer "B.Fab")
		)
		(fp_line
			(start 0.12065 -0.2794)
			(end -0.12065 -0.2794)
			(stroke
				(width 0.1)
				(type default)
			)
			(layer "B.Fab")
		)
		(fp_line
			(start -0.12065 -0.2794)
			(end -0.12065 -0.3048)
			(stroke
				(width 0.1)
				(type default)
			)
			(layer "B.Fab")
		)
		(fp_line
			(start 0.12065 0.2794)
			(end 0.12065 0.3048)
			(stroke
				(width 0.1)
				(type default)
			)
			(layer "B.Fab")
		)
		(fp_line
			(start -0.120396 0.2794)
			(end 0.12065 0.2794)
			(stroke
				(width 0.1)
				(type default)
			)
			(layer "B.Fab")
		)
		(fp_line
			(start 0.67945 0.3048)
			(end 0.67945 -0.305054)
			(stroke
				(width 0.1)
				(type default)
			)
			(layer "B.Fab")
		)
		(fp_line
			(start 0.12065 0.3048)
			(end 0.67945 0.3048)
			(stroke
				(width 0.1)
				(type default)
			)
			(layer "B.Fab")
		)
		(fp_line
			(start -0.120396 0.3048)
			(end -0.120396 0.2794)
			(stroke
				(width 0.1)
				(type default)
			)
			(layer "B.Fab")
		)
		(fp_line
			(start -0.67945 0.3048)
			(end -0.120396 0.3048)
			(stroke
				(width 0.1)
				(type default)
			)
			(layer "B.Fab")
		)
		(pad "1" smd circle
			(at 0.40005 0 270)
			(size 0 0)
			(layers "B.Cu" "B.Mask" "B.Paste")
			(net "P1V2_CPU0_USB2_DVDD12")
		)
		(pad "2" smd circle
			(at -0.40005 0 270)
			(size 0 0)
			(layers "B.Cu" "B.Mask" "B.Paste")
			(net "GND")
		)
	)
	(footprint ""
		(layer "B.Cu")
		(at 16.550386 -196.952616 -90)
		(property "Reference" "R773"
			(at 0 0 90)
			(layer "B.SilkS")
			(hide yes)
			(effects
				(font
					(size 1.27 1.27)
				)
				(justify mirror)
			)
		)
		(property "Value" ""
			(at 0 0 90)
			(layer "B.Fab")
			(effects
				(font
					(size 1.27 1.27)
				)
				(justify mirror)
			)
		)
		(duplicate_pad_numbers_are_jumpers no)
		(fp_line
			(start -0.7874 0.4064)
			(end 0.7874 0.4064)
			(stroke
				(width 0.1524)
				(type default)
			)
			(layer "B.SilkS")
		)
		(fp_line
			(start 0.7874 0.4064)
			(end 0.7874 -0.4064)
			(stroke
				(width 0.1524)
				(type default)
			)
			(layer "B.SilkS")
		)
		(fp_line
			(start -0.7874 -0.4064)
			(end -0.7874 0.4064)
			(stroke
				(width 0.1524)
				(type default)
			)
			(layer "B.SilkS")
		)
		(fp_line
			(start 0.7874 -0.4064)
			(end -0.7874 -0.4064)
			(stroke
				(width 0.1524)
				(type default)
			)
			(layer "B.SilkS")
		)
		(fp_line
			(start -0.67945 0.3048)
			(end -0.120396 0.3048)
			(stroke
				(width 0.1)
				(type default)
			)
			(layer "B.Fab")
		)
		(fp_line
			(start -0.120396 0.3048)
			(end -0.120396 0.2794)
			(stroke
				(width 0.1)
				(type default)
			)
			(layer "B.Fab")
		)
		(fp_line
			(start 0.12065 0.3048)
			(end 0.67945 0.3048)
			(stroke
				(width 0.1)
				(type default)
			)
			(layer "B.Fab")
		)
		(fp_line
			(start 0.67945 0.3048)
			(end 0.67945 -0.305054)
			(stroke
				(width 0.1)
				(type default)
			)
			(layer "B.Fab")
		)
		(fp_line
			(start -0.120396 0.2794)
			(end 0.12065 0.2794)
			(stroke
				(width 0.1)
				(type default)
			)
			(layer "B.Fab")
		)
		(fp_line
			(start 0.12065 0.2794)
			(end 0.12065 0.3048)
			(stroke
				(width 0.1)
				(type default)
			)
			(layer "B.Fab")
		)
		(fp_line
			(start -0.12065 -0.2794)
			(end -0.12065 -0.3048)
			(stroke
				(width 0.1)
				(type default)
			)
			(layer "B.Fab")
		)
		(fp_line
			(start 0.12065 -0.2794)
			(end -0.12065 -0.2794)
			(stroke
				(width 0.1)
				(type default)
			)
			(layer "B.Fab")
		)
		(fp_line
			(start -0.67945 -0.3048)
			(end -0.67945 0.3048)
			(stroke
				(width 0.1)
				(type default)
			)
			(layer "B.Fab")
		)
		(fp_line
			(start -0.12065 -0.3048)
			(end -0.67945 -0.3048)
			(stroke
				(width 0.1)
				(type default)
			)
			(layer "B.Fab")
		)
		(fp_line
			(start 0.12065 -0.305054)
			(end 0.12065 -0.2794)
			(stroke
				(width 0.1)
				(type default)
			)
			(layer "B.Fab")
		)
		(fp_line
			(start 0.67945 -0.305054)
			(end 0.12065 -0.305054)
			(stroke
				(width 0.1)
				(type default)
			)
			(layer "B.Fab")
		)
		(pad "1" smd circle
			(at 0.40005 0 90)
			(size 0 0)
			(layers "B.Cu" "B.Mask" "B.Paste")
			(net "PD_CHF_CPU1_DIMM_SAA")
		)
		(pad "2" smd circle
			(at -0.40005 0 90)
			(size 0 0)
			(layers "B.Cu" "B.Mask" "B.Paste")
			(net "GND")
		)
	)
	(footprint ""
		(layer "B.Cu")
		(at 156.151834 -321.814952 180)
		(property "Reference" "R548"
			(at 0 0 0)
			(layer "B.SilkS")
			(hide yes)
			(effects
				(font
					(size 1.27 1.27)
				)
				(justify mirror)
			)
		)
		(property "Value" ""
			(at 0 0 0)
			(layer "B.Fab")
			(effects
				(font
					(size 1.27 1.27)
				)
				(justify mirror)
			)
		)
		(duplicate_pad_numbers_are_jumpers no)
		(fp_line
			(start 0.7874 0.4064)
			(end 0.7874 -0.4064)
			(stroke
				(width 0.1524)
				(type default)
			)
			(layer "B.SilkS")
		)
		(fp_line
			(start 0.7874 -0.4064)
			(end -0.7874 -0.4064)
			(stroke
				(width 0.1524)
				(type default)
			)
			(layer "B.SilkS")
		)
		(fp_line
			(start -0.7874 0.4064)
			(end 0.7874 0.4064)
			(stroke
				(width 0.1524)
				(type default)
			)
			(layer "B.SilkS")
		)
		(fp_line
			(start -0.7874 -0.4064)
			(end -0.7874 0.4064)
			(stroke
				(width 0.1524)
				(type default)
			)
			(layer "B.SilkS")
		)
		(fp_line
			(start 0.67945 0.3048)
			(end 0.67945 -0.305054)
			(stroke
				(width 0.1)
				(type default)
			)
			(layer "B.Fab")
		)
		(fp_line
			(start 0.67945 -0.305054)
			(end 0.12065 -0.305054)
			(stroke
				(width 0.1)
				(type default)
			)
			(layer "B.Fab")
		)
		(fp_line
			(start 0.12065 0.3048)
			(end 0.67945 0.3048)
			(stroke
				(width 0.1)
				(type default)
			)
			(layer "B.Fab")
		)
		(fp_line
			(start 0.12065 0.2794)
			(end 0.12065 0.3048)
			(stroke
				(width 0.1)
				(type default)
			)
			(layer "B.Fab")
		)
		(fp_line
			(start 0.12065 -0.2794)
			(end -0.12065 -0.2794)
			(stroke
				(width 0.1)
				(type default)
			)
			(layer "B.Fab")
		)
		(fp_line
			(start 0.12065 -0.305054)
			(end 0.12065 -0.2794)
			(stroke
				(width 0.1)
				(type default)
			)
			(layer "B.Fab")
		)
		(fp_line
			(start -0.120396 0.3048)
			(end -0.120396 0.2794)
			(stroke
				(width 0.1)
				(type default)
			)
			(layer "B.Fab")
		)
		(fp_line
			(start -0.120396 0.2794)
			(end 0.12065 0.2794)
			(stroke
				(width 0.1)
				(type default)
			)
			(layer "B.Fab")
		)
		(fp_line
			(start -0.12065 -0.2794)
			(end -0.12065 -0.3048)
			(stroke
				(width 0.1)
				(type default)
			)
			(layer "B.Fab")
		)
		(fp_line
			(start -0.12065 -0.3048)
			(end -0.67945 -0.3048)
			(stroke
				(width 0.1)
				(type default)
			)
			(layer "B.Fab")
		)
		(fp_line
			(start -0.67945 0.3048)
			(end -0.120396 0.3048)
			(stroke
				(width 0.1)
				(type default)
			)
			(layer "B.Fab")
		)
		(fp_line
			(start -0.67945 -0.3048)
			(end -0.67945 0.3048)
			(stroke
				(width 0.1)
				(type default)
			)
			(layer "B.Fab")
		)
		(pad "1" smd circle
			(at 0.40005 0)
			(size 0 0)
			(layers "B.Cu" "B.Mask" "B.Paste")
			(net "CPU1_SLP_S5_N")
		)
		(pad "2" smd circle
			(at -0.40005 0)
			(size 0 0)
			(layers "B.Cu" "B.Mask" "B.Paste")
			(net "PVDD18_S5_P1")
		)
	)
	(footprint ""
		(layer "B.Cu")
		(at 337.24596 -396.393162 -90)
		(property "Reference" "C650"
			(at 0 0 90)
			(layer "B.SilkS")
			(hide yes)
			(effects
				(font
					(size 1.27 1.27)
				)
				(justify mirror)
			)
		)
		(property "Value" ""
			(at 0 0 90)
			(layer "B.Fab")
			(effects
				(font
					(size 1.27 1.27)
				)
				(justify mirror)
			)
		)
		(duplicate_pad_numbers_are_jumpers no)
		(fp_line
			(start -0.299974 0.150114)
			(end 0.299974 0.150114)
			(stroke
				(width 0.1)
				(type default)
			)
			(layer "B.Fab")
		)
		(fp_line
			(start 0.299974 0.150114)
			(end 0.299974 -0.150114)
			(stroke
				(width 0.1)
				(type default)
			)
			(layer "B.Fab")
		)
		(fp_line
			(start -0.299974 -0.150114)
			(end -0.299974 0.150114)
			(stroke
				(width 0.1)
				(type default)
			)
			(layer "B.Fab")
		)
		(fp_line
			(start 0.299974 -0.150114)
			(end -0.299974 -0.150114)
			(stroke
				(width 0.1)
				(type default)
			)
			(layer "B.Fab")
		)
		(pad "1" smd rect
			(at 0.2667 0 90)
			(size 0.3048 0.381)
			(layers "B.Cu" "B.Mask" "B.Paste")
			(net "P0V9_CPU0_RT1_2A")
		)
		(pad "2" smd rect
			(at -0.2667 0 90)
			(size 0.3048 0.381)
			(layers "B.Cu" "B.Mask" "B.Paste")
			(net "GND")
		)
	)
)
